# BASEBOARD_FAB2 (Tioga Pass) — schematic netlist excerpt (pin names and nets, part order shuffled) for the footprints in the layout excerpt that follows; sources: Cadence DE-HDL packaged netlist, KiCad conversion of Wiwynn_Tioga_Pass_MB.brd

R7B16  RES  7.87K 1.0% CHIP  pkg 0402  page 232 : A = VR_COMP_RC_PVPP_DEF ; B = VR_FB_PVPP_DEF
C1A8  CAP  0.220UF 16V 10% X7R  pkg 0402  page 227 : A = VR_PVDDQ_KLM_PH2_BOOT ; B = VR_PVDDQ_KLM_PH2_PHASE
R10W4  RES  221 1.0% CHIP  pkg 0402  page 251 : A = PUMP_PWM_OUT_BUF ; B = PUMP_PWM_OUT_R

(kicad_pcb
	(version 20260206)
	(generator "pcbnew")
	(generator_version "10.0")
	(general
		(thickness 1.6)
		(legacy_teardrops no)
	)
	(paper "A4")
	(title_block
		(title "Wiwynn_Tioga_Pass_MB.brd")
		(comment 1 "Tioga Pass / footprints 1720-1722 of 4770")
	)
	(layers
		(0 "F.Cu" signal "TOP")
		(4 "In1.Cu" signal "L2GND")
		(6 "In2.Cu" signal "L3")
		(8 "In3.Cu" signal "L4GND")
		(10 "In4.Cu" signal "L5")
		(12 "In5.Cu" signal "L6GND")
		(14 "In6.Cu" signal "L7VCC")
		(16 "In7.Cu" signal "L8VCC")
		(18 "In8.Cu" signal "L9GND")
		(20 "In9.Cu" signal "L10")
		(22 "In10.Cu" signal "L11GND")
		(24 "In11.Cu" signal "L12")
		(26 "In12.Cu" signal "L13GND")
		(2 "B.Cu" signal "BOTTOM")
		(9 "F.Adhes" user "F.Adhesive")
		(11 "B.Adhes" user "B.Adhesive")
		(13 "F.Paste" user "Package Geometry/Pastemask Top")
		(15 "B.Paste" user "Package Geometry/Pastemask Bottom")
		(5 "F.SilkS" user "Ref Des/Silkscreen Top")
		(7 "B.SilkS" user "Ref Des/Silkscreen Bottom")
		(1 "F.Mask" user "Board Geometry/Soldermask Top")
		(3 "B.Mask" user "Board Geometry/Soldermask Bottom")
		(17 "Dwgs.User" user "User.Drawings")
		(19 "Cmts.User" user "User.Comments")
		(21 "Eco1.User" user "User.Eco1")
		(23 "Eco2.User" user "User.Eco2")
		(25 "Edge.Cuts" user "Board Geometry/Outline")
		(27 "Margin" user)
		(31 "F.CrtYd" user "Package Geometry/Place Bound Top")
		(29 "B.CrtYd" user "Package Geometry/Place Bound Bottom")
		(35 "F.Fab" user "Ref Des/Assembly Top")
		(33 "B.Fab" user "Ref Des/Assembly Bottom")
	)
	(footprint ""
		(layer "F.Cu")
		(at 429.895 -22.86 -90)
		(property "Reference" "R10W4"
			(at -0.8382 -0.67818 270)
			(unlocked yes)
			(layer "F.SilkS")
			(effects
				(font
					(size 0.4064 0.254)
					(thickness 0.1524)
				)
				(justify left)
			)
		)
		(property "Value" ""
			(at 0 0 270)
			(layer "F.Fab")
			(effects
				(font
					(size 1.27 1.27)
				)
			)
		)
		(duplicate_pad_numbers_are_jumpers no)
		(fp_poly
			(pts
				(xy -0.2794 -0.1016) (xy 0.2794 -0.1016) (xy 0.2794 0.9906) (xy -0.2794 0.9906)
			)
			(stroke
				(width 0)
				(type default)
			)
			(fill no)
			(layer "F.CrtYd")
		)
		(fp_line
			(start -0.2794 0.9906)
			(end 0.2794 0.9906)
			(stroke
				(width 0.1)
				(type default)
			)
			(layer "F.Fab")
		)
		(fp_line
			(start 0.2794 0.9906)
			(end 0.2794 -0.1016)
			(stroke
				(width 0.1)
				(type default)
			)
			(layer "F.Fab")
		)
		(fp_line
			(start -0.2794 -0.1016)
			(end -0.2794 0.9906)
			(stroke
				(width 0.1)
				(type default)
			)
			(layer "F.Fab")
		)
		(fp_line
			(start 0.2794 -0.1016)
			(end -0.2794 -0.1016)
			(stroke
				(width 0.1)
				(type default)
			)
			(layer "F.Fab")
		)
		(pad "1" smd rect
			(at 0 0 270)
			(size 0.508 0.508)
			(layers "F.Cu" "F.Mask" "F.Paste")
			(net "PUMP_PWM_OUT_BUF")
		)
		(pad "2" smd rect
			(at 0 0.889 270)
			(size 0.508 0.508)
			(layers "F.Cu" "F.Mask" "F.Paste")
			(net "PUMP_PWM_OUT_R")
		)
		(zone
			(layer "F.Cu")
			(hatch none 0.5)
			(connect_pads
				(clearance 0)
			)
			(min_thickness 0.25)
			(keepout
				(tracks not_allowed)
				(vias allowed)
				(pads allowed)
				(copperpour not_allowed)
				(footprints allowed)
			)
			(placement
				(enabled no)
				(sheetname "")
			)
			(fill
				(thermal_gap 0.5)
				(thermal_bridge_width 0.5)
				(island_removal_mode 0)
			)
			(polygon
				(pts
					(xy 429.26 -23.114) (xy 429.26 -22.606) (xy 429.641 -22.606) (xy 429.641 -23.114)
				)
			)
		)
		(zone
			(layer "F.Cu")
			(hatch none 0.5)
			(connect_pads
				(clearance 0)
			)
			(min_thickness 0.25)
			(keepout
				(tracks allowed)
				(vias not_allowed)
				(pads allowed)
				(copperpour not_allowed)
				(footprints allowed)
			)
			(placement
				(enabled no)
				(sheetname "")
			)
			(fill
				(thermal_gap 0.5)
				(thermal_bridge_width 0.5)
				(island_removal_mode 0)
			)
			(polygon
				(pts
					(xy 429.641 -23.114) (xy 429.641 -22.606) (xy 429.26 -22.606) (xy 429.26 -23.114)
				)
			)
		)
	)
	(footprint ""
		(layer "F.Cu")
		(at 341.6046 -127.4445 180)
		(property "Reference" "R7B16"
			(at 0 0 180)
			(layer "F.SilkS")
			(hide yes)
			(effects
				(font
					(size 1.27 1.27)
				)
			)
		)
		(property "Value" ""
			(at 0 0 180)
			(layer "F.Fab")
			(effects
				(font
					(size 1.27 1.27)
				)
			)
		)
		(duplicate_pad_numbers_are_jumpers no)
		(fp_poly
			(pts
				(xy -0.2794 -0.1016) (xy 0.2794 -0.1016) (xy 0.2794 0.9906) (xy -0.2794 0.9906)
			)
			(stroke
				(width 0)
				(type default)
			)
			(fill no)
			(layer "F.CrtYd")
		)
		(fp_line
			(start 0.2794 0.9906)
			(end 0.2794 -0.1016)
			(stroke
				(width 0.1)
				(type default)
			)
			(layer "F.Fab")
		)
		(fp_line
			(start 0.2794 -0.1016)
			(end -0.2794 -0.1016)
			(stroke
				(width 0.1)
				(type default)
			)
			(layer "F.Fab")
		)
		(fp_line
			(start -0.2794 0.9906)
			(end 0.2794 0.9906)
			(stroke
				(width 0.1)
				(type default)
			)
			(layer "F.Fab")
		)
		(fp_line
			(start -0.2794 -0.1016)
			(end -0.2794 0.9906)
			(stroke
				(width 0.1)
				(type default)
			)
			(layer "F.Fab")
		)
		(pad "1" smd rect
			(at 0 0 180)
			(size 0.508 0.508)
			(layers "F.Cu" "F.Mask" "F.Paste")
			(net "VR_COMP_RC_PVPP_DEF")
		)
		(pad "2" smd rect
			(at 0 0.889 180)
			(size 0.508 0.508)
			(layers "F.Cu" "F.Mask" "F.Paste")
			(net "VR_FB_PVPP_DEF")
		)
		(zone
			(layer "F.Cu")
			(hatch none 0.5)
			(connect_pads
				(clearance 0)
			)
			(min_thickness 0.25)
			(keepout
				(tracks not_allowed)
				(vias allowed)
				(pads allowed)
				(copperpour not_allowed)
				(footprints allowed)
			)
			(placement
				(enabled no)
				(sheetname "")
			)
			(fill
				(thermal_gap 0.5)
				(thermal_bridge_width 0.5)
				(island_removal_mode 0)
			)
			(polygon
				(pts
					(xy 341.8586 -128.0795) (xy 341.3506 -128.0795) (xy 341.3506 -127.6985) (xy 341.8586 -127.6985)
				)
			)
		)
		(zone
			(layer "F.Cu")
			(hatch none 0.5)
			(connect_pads
				(clearance 0)
			)
			(min_thickness 0.25)
			(keepout
				(tracks allowed)
				(vias not_allowed)
				(pads allowed)
				(copperpour not_allowed)
				(footprints allowed)
			)
			(placement
				(enabled no)
				(sheetname "")
			)
			(fill
				(thermal_gap 0.5)
				(thermal_bridge_width 0.5)
				(island_removal_mode 0)
			)
			(polygon
				(pts
					(xy 341.8586 -127.6985) (xy 341.3506 -127.6985) (xy 341.3506 -128.0795) (xy 341.8586 -128.0795)
				)
			)
		)
	)
	(footprint ""
		(layer "F.Cu")
		(at -2.856484 -149.29231 90)
		(property "Reference" "C1A8"
			(at 0 0 90)
			(layer "F.SilkS")
			(hide yes)
			(effects
				(font
					(size 1.27 1.27)
				)
			)
		)
		(property "Value" ""
			(at 0 0 90)
			(layer "F.Fab")
			(effects
				(font
					(size 1.27 1.27)
				)
			)
		)
		(duplicate_pad_numbers_are_jumpers no)
		(fp_poly
			(pts
				(xy 0.3048 -0.1016) (xy 0.3048 0.9906) (xy -0.3048 0.9906) (xy -0.3048 -0.1016)
			)
			(stroke
				(width 0)
				(type default)
			)
			(fill no)
			(layer "F.CrtYd")
		)
		(fp_line
			(start 0.3048 -0.1016)
			(end -0.3048 -0.1016)
			(stroke
				(width 0.1)
				(type default)
			)
			(layer "F.Fab")
		)
		(fp_line
			(start -0.3048 -0.1016)
			(end -0.3048 0.9906)
			(stroke
				(width 0.1)
				(type default)
			)
			(layer "F.Fab")
		)
		(fp_line
			(start 0.3048 0.9906)
			(end 0.3048 -0.1016)
			(stroke
				(width 0.1)
				(type default)
			)
			(layer "F.Fab")
		)
		(fp_line
			(start -0.3048 0.9906)
			(end 0.3048 0.9906)
			(stroke
				(width 0.1)
				(type default)
			)
			(layer "F.Fab")
		)
		(pad "1" smd rect
			(at 0 0 90)
			(size 0.508 0.508)
			(layers "F.Cu" "F.Mask" "F.Paste")
			(net "VR_PVDDQ_KLM_PH2_BOOT")
		)
		(pad "2" smd rect
			(at 0 0.889 90)
			(size 0.508 0.508)
			(layers "F.Cu" "F.Mask" "F.Paste")
			(net "VR_PVDDQ_KLM_PH2_PHASE")
		)
		(zone
			(layer "F.Cu")
			(hatch none 0.5)
			(connect_pads
				(clearance 0)
			)
			(min_thickness 0.25)
			(keepout
				(tracks allowed)
				(vias not_allowed)
				(pads allowed)
				(copperpour not_allowed)
				(footprints allowed)
			)
			(placement
				(enabled no)
				(sheetname "")
			)
			(fill
				(thermal_gap 0.5)
				(thermal_bridge_width 0.5)
				(island_removal_mode 0)
			)
			(polygon
				(pts
					(xy -2.602484 -149.03831) (xy -2.602484 -149.54631) (xy -2.221484 -149.54631) (xy -2.221484 -149.03831)
				)
			)
		)
		(zone
			(layer "F.Cu")
			(hatch none 0.5)
			(connect_pads
				(clearance 0)
			)
			(min_thickness 0.25)
			(keepout
				(tracks not_allowed)
				(vias allowed)
				(pads allowed)
				(copperpour not_allowed)
				(footprints allowed)
			)
			(placement
				(enabled no)
				(sheetname "")
			)
			(fill
				(thermal_gap 0.5)
				(thermal_bridge_width 0.5)
				(island_removal_mode 0)
			)
			(polygon
				(pts
					(xy -2.221484 -149.03831) (xy -2.221484 -149.54631) (xy -2.602484 -149.54631) (xy -2.602484 -149.03831)
				)
			)
		)
	)
)
